FILE_TYPE = CONNECTIVITY;
{Allegro Design Entry HDL 17.2-2016 S081 (4005846) 1/11/2022}
"PAGE_NUMBER" = 327;
0"NC";
1"P12V_AUX";
2"P3V3_AUX\g";
3"P3V3_AUX\g";
4"P3V3_AUX\g";
5"P12V_PSU";
6"P3V3_AUX\g";
7"GND\g";
8"GND\g";
9"GND\g";
10"GND\g";
11"GND\g";
12"GND\g";
13"SMB_SML1_PMBUS_HSC_MODULE_SCL";
14"SMB_SML1_PMBUS_HSC_MODULE_SDA";
15"IRQ_SML1_PMBUS_ALERT_N";
16"P12V_HSC_ADC_P";
17"HSC_EN";
18"SMB_SML1_PMBUS_HSC_SDA";
19"IRQ_HSC_FAULT_N";
20"MB0_P12V_STBY_PWRGD";
21"P12V_HSC_TEMP_D+";
22"P12V_HSC_TEMP_R";
23"SMB_SML1_PMBUS_HSC_SCL";
24"P12V_HSC_SENSE1_N";
25"P12V_HSC_SENSE2_P";
26"P12V_HSC_SENSE2_N";
27"P12V_HSC_SENSE1_P";
28"P12V_HSC_ADC_N";
29"P12V_HSC_GATE1";
30"P12V_HSC_GATE2";
31"SMB_LM75_0_3V3AUX_SCL";
32"P12V_HSC_T_CRIT_R_N";
33"P12V_HSC_TEMP_E";
34"P12V_HSC_T_CRIT_N";
35"P12V_HSC_TEMP_D-";
36"SMB_LM75_0_3V3AUX_SDA";
37"HSC_CSOUT";
38"P12V_HSC_TEMP_SCL";
39"P12V_HSC_TEMP_SDA";
40"P12V_HSC_TEMP_ALERT_N";
41"P12V_HSC_TEMP_ALERT_R_N";
42"HSC_TYPE_ADC";
%"NCT7718W"
"1","(3200,250)","0","pure_quanta","I10";
;
PART_NUMBER"AL007718001"
MATERIAL"EMPTY"
ROOM"HSC1_BOM2"
PART_TYPE"SMLF"
VALUE"NCT7718W"
LOCATION"U345"
NEEDS_NO_SIZE"TRUE"
CDS_LIB"pure_quanta"
CDS_LMAN_SYM_OUTLINE"-250,200,250,-200"
$SEC"1"
CDS_SEC"1";
"SCL"
$PN"8"38;
"SDA"
$PN"7"39;
"ALERT# \B"
$PN"6"40;
"GND"
$PN"5"9;
"T_CRIT# \B"
$PN"4"34;
"D-"
$PN"3"35;
"D+"
$PN"2"21;
"VDD"
$PN"1"3;
%"Q_RES"
"1","(3425,-325)","0","pure_quanta","I11";
;
PART_NUMBER"CS00002JB13"
ROOM"HSC1_BOM2"
PACK_TYPE"0402LF"
MATERIAL"EMPTY"
WATTAGE"1/16W"
VALUE"0"
TOLERANCE"5%"
LOCATION"R4896"
CDS_LIB"pure_quanta"
$SEC"1"
CDS_SEC"1";
"B"
$PN"2"32;
"A"
$PN"1"34;
%"UNIVERSAL_GND"
"1","(3700,-25)","0","logical_power","I13";
;
CDS_LIB"logical_power"
HDL_POWER"GND";
"A"9;
%"Q_RES"
"1","(4475,200)","0","pure_quanta","I14";
;
PART_NUMBER"CS00002JB13"
ROOM"HSC1_BOM2"
WATTAGE"1/16W"
MATERIAL"EMPTY"
PACK_TYPE"0402LF"
VALUE"0"
TOLERANCE"5%"
$LOCATION"R4684"
CDS_LIB"pure_quanta"
CDS_LOCATION"R4684"
$SEC"1"
CDS_SEC"1";
"B"
$PN"2"41;
"A"
$PN"1"40;
%"Q_RES"
"1","(4475,400)","0","pure_quanta","I15";
;
PART_NUMBER"CS00002JB13"
MATERIAL"EMPTY"
ROOM"HSC1_BOM2"
WATTAGE"1/16W"
PACK_TYPE"0402LF"
VALUE"0"
TOLERANCE"5%"
LOCATION"R4894"
CDS_LIB"pure_quanta"
$SEC"1"
CDS_SEC"1";
"B"
$PN"2"31;
"A"
$PN"1"38;
%"Q_RES"
"1","(4475,300)","0","pure_quanta","I16";
;
PART_NUMBER"CS00002JB13"
ROOM"HSC1_BOM2"
MATERIAL"EMPTY"
TOLERANCE"5%"
WATTAGE"1/16W"
PACK_TYPE"0402LF"
VALUE"0"
LOCATION"R4895"
CDS_LIB"pure_quanta"
$SEC"1"
CDS_SEC"1";
"B"
$PN"2"36;
"A"
$PN"1"39;
%"Q_RES"
"2","(4800,-100)","0","pure_quanta","I17";
;
PART_NUMBER"CS31052FB03"
ROOM"HSC1_BOM2"
VALUE"10.5K"
MATERIAL"EMPTY"
PACK_TYPE"0402LF"
TOLERANCE"1%"
WATTAGE"1/16W"
$LOCATION"R4686"
CDS_LIB"pure_quanta"
CDS_LOCATION"R4686"
$SEC"1"
CDS_SEC"1";
"A"
$PN"1"4;
"B"
$PN"2"32;
%"UNIVERSAL_POWER"
"1","(4800,100)","0","logical_power","I18";
;
HDL_POWER"P3V3_AUX"
CDS_LIB"logical_power";
"A"4;
%"Q_RES"
"2","(4800,750)","0","pure_quanta","I23";
;
PART_NUMBER"CS31052FB03"
WATTAGE"1/16W"
MATERIAL"EMPTY"
PACK_TYPE"0402LF"
ROOM"HSC1_BOM2"
TOLERANCE"1%"
VALUE"10.5K"
$LOCATION"R4685"
CDS_LIB"pure_quanta"
CDS_LOCATION"R4685"
$SEC"1"
CDS_SEC"1";
"A"
$PN"1"2;
"B"
$PN"2"41;
%"UNIVERSAL_POWER"
"1","(4800,975)","0","logical_power","I24";
;
HDL_POWER"P3V3_AUX"
CDS_LIB"logical_power";
"A"2;
%"Q_RES"
"1","(1925,2325)","0","pure_quanta","I25";
;
PART_NUMBER"CS00002JB13"
MATERIAL"CHIP"
VALUE"0"
$LOCATION"R4696"
PACK_TYPE"0402LF"
WATTAGE"1/16W"
TOLERANCE"5%"
CDS_LIB"pure_quanta"
CDS_LOCATION"R4696"
$SEC"1"
CDS_SEC"1";
"B"
$PN"2"14;
"A"
$PN"1"18;
%"Q_RES"
"1","(1925,2375)","0","pure_quanta","I26";
;
PART_NUMBER"CS00002JB13"
MATERIAL"CHIP"
VALUE"0"
$LOCATION"R4695"
PACK_TYPE"0402LF"
WATTAGE"1/16W"
TOLERANCE"5%"
CDS_LIB"pure_quanta"
CDS_LOCATION"R4695"
$SEC"1"
CDS_SEC"1";
"B"
$PN"2"13;
"A"
$PN"1"23;
%"UNIVERSAL_GND"
"1","(3200,1850)","0","logical_power","I33";
;
HDL_POWER"GND"
CDS_LIB"logical_power";
"A"11;
%"SCONN21_9193031121LF"
"1","(3650,2350)","2","pure_quanta","I34";
;
PART_NUMBER"DFHS21FS003"
VALUE"SCONN21_91930-31121LF"
ROOM"HSC1_BOM2"
MATERIAL"EMPTY"
PART_TYPE"SMLF"
LOCATION"PJ42"
NEEDS_NO_SIZE"TRUE"
CDS_LMAN_SYM_OUTLINE"-150,425,150,-425"
CDS_LIB"pure_quanta"
$SEC"1"
CDS_SEC"1";
"21"
$PN"21"11;
"20"
$PN"20"15;
"19"
$PN"19"14;
"18"
$PN"18"13;
"17"
$PN"17"42;
"16"
$PN"16"37;
"15"
$PN"15"20;
"14"
$PN"14"17;
"13"
$PN"13"19;
"12"
$PN"12"6;
"11"
$PN"11"8;
"10"
$PN"10"1;
"9"
$PN"9"30;
"8"
$PN"8"29;
"7"
$PN"7"16;
"6"
$PN"6"28;
"G2"
$PN"G2"11;
"G1"
$PN"G1"11;
"2"
$PN"2"27;
"5"
$PN"5"26;
"4"
$PN"4"25;
"3"
$PN"3"24;
"1"
$PN"1"5;
%"UNIVERSAL_POWER"
"1","(2950,2775)","0","logical_power","I35";
;
HDL_POWER"P3V3_AUX"
CDS_LIB"logical_power";
"A"6;
%"UNIVERSAL_GND"
"1","(4050,2000)","0","logical_power","I36";
;
HDL_POWER"GND"
CDS_LIB"logical_power";
"A"8;
%"UNIVERSAL_GND"
"1","(4425,1775)","0","logical_power","I37";
;
HDL_POWER"GND"
CDS_LIB"logical_power";
"A"7;
%"Q_CAP"
"1","(4425,1950)","0","pure_quanta","I38";
;
PART_NUMBER"CH4104K1B00"
ROOM"HSC1_BOM2"
VALUE"0.1UF"
VOLTAGE"25V"
TOLERANCE"10%"
MATERIAL"EMPTY"
PACK_TYPE"0402"
$LOCATION"PC1789"
CDS_LIB"pure_quanta"
CDS_LOCATION"PC1789"
$SEC"1"
CDS_SEC"1";
"B"
$PN"2"7;
"A"
$PN"1"1;
%"Q_RES"
"1","(1725,-50)","0","pure_quanta","I4";
;
PART_NUMBER"CS04992FB07"
ROOM"HSC1_BOM2"
WATTAGE"1/16W"
MATERIAL"EMPTY"
PACK_TYPE"0402LF"
TOLERANCE"1%"
VALUE"49.9"
LOCATION"R4893"
CDS_LIB"pure_quanta"
$SEC"1"
CDS_SEC"1";
"B"
$PN"2"35;
"A"
$PN"1"33;
%"UNIVERSAL_POWER"
"1","(5175,2275)","0","logical_power","I46";
;
HDL_POWER"P12V_AUX"
CDS_LIB"logical_power";
"A"1;
%"UNIVERSAL_POWER"
"1","(4550,2775)","0","logical_power","I48";
;
HDL_POWER"P12V_PSU"
CDS_LIB"logical_power"
ROOM"AUX_SW"
BOM_COST"MIO_VRD_SB";
"A"5;
%"MMBT3904"
"1","(925,125)","2","pure_quanta","I49";
;
PART_NUMBER"BA039040039"
VALUE"MMBT3904    "
ROOM"HSC1_BOM2"
PACK_TYPE"SMLF"
MATERIAL"EMPTY"
LOCATION"U365"
CDS_LIB"pure_quanta"
NEEDS_NO_SIZE"TRUE"
$SEC"1"
CDS_SEC"1";
"3"
$PN"C"22;
"1"
$PN"B"22;
"2"
$PN"E"33;
%"Q_RES"
"1","(1750,300)","0","pure_quanta","I5";
;
PART_NUMBER"CS04992FB07"
TOLERANCE"1%"
WATTAGE"1/16W"
ROOM"HSC1_BOM2"
VALUE"49.9"
PACK_TYPE"0402LF"
MATERIAL"EMPTY"
LOCATION"R4892"
CDS_LIB"pure_quanta"
$SEC"1"
CDS_SEC"1";
"B"
$PN"2"21;
"A"
$PN"1"22;
%"GND"
"1","(2750,1600)","0","logical_power","I50";
;
CDS_LIB"logical_power"
SIZE"1B"
HDL_POWER"GND";
"A<SIZE-1..0>\NAC"12;
%"CONN3_210HP1030BR1"
"1","(2475,1750)","2","pure_quanta","I51";
;
PART_NUMBER"DFHD03MS213"
VALUE"CONN3_210-HP1-030BR1"
PART_TYPE"THLF"
MATERIAL"IO"
$LOCATION"JP10"
CDS_LIB"pure_quanta"
CDS_LMAN_SYM_OUTLINE"-50,100,50,-100"
NEEDS_NO_SIZE"TRUE"
CDS_LOCATION"JP10"
$SEC"1"
CDS_SEC"1";
"1"
$PN"1"13;
"2"
$PN"2"14;
"3"
$PN"3"12;
%"Q_CAP"
"1","(2050,150)","2","pure_quanta","I6";
;
PART_NUMBER"TMP_QCH21006K917"
ROOM"HSC1_BOM2"
VALUE"1000PF"
VOLTAGE"50V"
TOLERANCE"10%"
MATERIAL"EMPTY"
PACK_TYPE"0603"
LOCATION"C2459"
CDS_LIB"pure_quanta"
$SEC"1"
CDS_SEC"1";
"B"
$PN"2"35;
"A"
$PN"1"21;
%"UNIVERSAL_GND"
"1","(2275,425)","0","logical_power","I7";
;
CDS_LIB"logical_power"
HDL_POWER"GND";
"A"10;
%"Q_CAP"
"1","(2275,625)","0","pure_quanta","I8";
;
PART_NUMBER"CH4104K1B00"
PACK_TYPE"0402"
VOLTAGE"25V"
VALUE"0.1UF"
TOLERANCE"10%"
ROOM"HSC1_BOM2"
MATERIAL"EMPTY"
LOCATION"C2458"
CDS_LIB"pure_quanta"
$SEC"1"
CDS_SEC"1";
"B"
$PN"2"10;
"A"
$PN"1"3;
%"UNIVERSAL_POWER"
"1","(2275,1050)","0","logical_power","I9";
;
HDL_POWER"P3V3_AUX"
CDS_LIB"logical_power";
"A"3;
END.
